# S9S_MB_2U (Grand Teton) — schematic netlist excerpt (pin names and nets, part order shuffled) for the footprints in the layout excerpt that follows; sources: Cadence DE-HDL packaged netlist, KiCad conversion of 03242023_DA0F0TMBIJ0_F0T_Motherboard_J_brd_V01_OCP.brd

J117  PICOPROBE_BXA  DELTA-L 4.0 EMPTY  pkg TRIANG_LAUNCH_3PXB  page 308
  \1_p\  = DELTA_L_85_5INCH_IN6_DN
  \2_n\  = DELTA_L_85_5INCH_IN6_DP
  \3_g\  = DELTA_L_GND_1

(kicad_pcb
	(version 20260206)
	(generator "pcbnew")
	(generator_version "10.0")
	(general
		(thickness 1.6)
		(legacy_teardrops no)
	)
	(paper "A4")
	(title_block
		(title "03242023_DA0F0TMBIJ0_F0T_Motherboard_J_brd_V01_OCP.brd")
		(comment 1 "Grand Teton / footprints 5231-5231 of 6105")
	)
	(layers
		(0 "F.Cu" signal "TOP")
		(4 "In1.Cu" signal "GND")
		(6 "In2.Cu" signal "IN1")
		(8 "In3.Cu" signal "GND1")
		(10 "In4.Cu" signal "IN2")
		(12 "In5.Cu" signal "GND2")
		(14 "In6.Cu" signal "IN3")
		(16 "In7.Cu" signal "GND3")
		(18 "In8.Cu" signal "VCC")
		(20 "In9.Cu" signal "VCC1")
		(22 "In10.Cu" signal "GND4")
		(24 "In11.Cu" signal "IN4")
		(26 "In12.Cu" signal "GND5")
		(28 "In13.Cu" signal "IN5")
		(30 "In14.Cu" signal "GND6")
		(32 "In15.Cu" signal "IN6")
		(34 "In16.Cu" signal "GND7")
		(2 "B.Cu" signal "BOTTOM")
		(9 "F.Adhes" user "F.Adhesive")
		(11 "B.Adhes" user "B.Adhesive")
		(13 "F.Paste" user "Package Geometry/Pastemask Top")
		(15 "B.Paste" user "Package Geometry/Pastemask Bottom")
		(5 "F.SilkS" user "Ref Des/Silkscreen Top")
		(7 "B.SilkS" user "Ref Des/Silkscreen Bottom")
		(1 "F.Mask" user "Board Geometry/Soldermask Top")
		(3 "B.Mask" user "Board Geometry/Soldermask Bottom")
		(17 "Dwgs.User" user "User.Drawings")
		(19 "Cmts.User" user "User.Comments")
		(21 "Eco1.User" user "User.Eco1")
		(23 "Eco2.User" user "User.Eco2")
		(25 "Edge.Cuts" user "Board Geometry/Outline")
		(27 "Margin" user)
		(31 "F.CrtYd" user "Package Geometry/Place Bound Top")
		(29 "B.CrtYd" user "Package Geometry/Place Bound Bottom")
		(35 "F.Fab" user "Ref Des/Assembly Top")
		(33 "B.Fab" user "Ref Des/Assembly Bottom")
	)
	(footprint ""
		(layer "B.Cu")
		(at 378.099574 2.923794)
		(property "Reference" "J117"
			(at 4.651756 1.394206 270)
			(unlocked yes)
			(layer "B.SilkS")
			(effects
				(font
					(size 0.7874 0.5842)
					(thickness 0.1524)
				)
				(justify left mirror)
			)
		)
		(property "Value" ""
			(at 0 0 0)
			(layer "B.Fab")
			(effects
				(font
					(size 1.27 1.27)
				)
				(justify mirror)
			)
		)
		(duplicate_pad_numbers_are_jumpers no)
		(fp_line
			(start -1.2192 -2.1082)
			(end -1.2192 2.1082)
			(stroke
				(width 0.1524)
				(type default)
			)
			(layer "B.SilkS")
		)
		(fp_line
			(start -1.2192 2.1082)
			(end 1.2192 2.1082)
			(stroke
				(width 0.1524)
				(type default)
			)
			(layer "B.SilkS")
		)
		(fp_line
			(start 1.2192 -2.1082)
			(end -1.2192 -2.1082)
			(stroke
				(width 0.1524)
				(type default)
			)
			(layer "B.SilkS")
		)
		(fp_line
			(start 1.2192 2.1082)
			(end 1.2192 -2.1082)
			(stroke
				(width 0.1524)
				(type default)
			)
			(layer "B.SilkS")
		)
		(pad "" np_thru_hole circle
			(at -3.4671 -1.27 270)
			(size 1.0414 1.0414)
			(drill 1.0414)
			(layers "*.Cu" "*.Mask")
			(clearance 0.381)
			(thermal_gap 0.381)
		)
		(pad "" np_thru_hole circle
			(at -3.4671 1.27 270)
			(size 1.0414 1.0414)
			(drill 1.0414)
			(layers "*.Cu" "*.Mask")
			(clearance 0.381)
			(thermal_gap 0.381)
		)
		(pad "" np_thru_hole circle
			(at 2.8829 -1.27 270)
			(size 1.0414 1.0414)
			(drill 1.0414)
			(layers "*.Cu" "*.Mask")
			(clearance 0.381)
			(thermal_gap 0.381)
		)
		(pad "" np_thru_hole circle
			(at 2.8829 1.27 270)
			(size 1.0414 1.0414)
			(drill 1.0414)
			(layers "*.Cu" "*.Mask")
			(clearance 0.381)
			(thermal_gap 0.381)
		)
		(pad "1" smd rect
			(at -0.8255 -0.249936 270)
			(size 0.3048 0.508)
			(layers "B.Cu" "B.Mask" "B.Paste")
			(net "DELTA_L_85_5INCH_IN6_DN")
		)
		(pad "2" smd rect
			(at -0.8255 0.249936 270)
			(size 0.3048 0.508)
			(layers "B.Cu" "B.Mask" "B.Paste")
			(net "DELTA_L_85_5INCH_IN6_DP")
		)
		(pad "3" smd circle
			(at 0 0 180)
			(size 0 0)
			(layers "B.Cu" "B.Mask" "B.Paste")
			(net "DELTA_L_GND_1")
		)
		(zone
			(layers "F.Cu" "B.Cu" "In1.Cu" "In2.Cu" "In3.Cu" "In4.Cu" "In5.Cu" "In6.Cu"
				"In7.Cu" "In8.Cu" "In9.Cu" "In10.Cu" "In11.Cu" "In12.Cu" "In13.Cu" "In14.Cu"
				"In15.Cu" "In16.Cu"
			)
			(hatch none 0.5)
			(connect_pads
				(clearance 0)
			)
			(min_thickness 0.25)
			(keepout
				(tracks not_allowed)
				(vias allowed)
				(pads allowed)
				(copperpour not_allowed)
				(footprints allowed)
			)
			(placement
				(enabled no)
				(sheetname "")
			)
			(fill
				(thermal_gap 0.5)
				(thermal_bridge_width 0.5)
				(island_removal_mode 0)
			)
			(polygon
				(pts
					(arc
						(start 375.559574 1.653794)
						(mid 373.705374 1.653794)
						(end 375.559574 1.653794)
					)
				)
			)
		)
		(zone
			(layers "F.Cu" "B.Cu" "In1.Cu" "In2.Cu" "In3.Cu" "In4.Cu" "In5.Cu" "In6.Cu"
				"In7.Cu" "In8.Cu" "In9.Cu" "In10.Cu" "In11.Cu" "In12.Cu" "In13.Cu" "In14.Cu"
				"In15.Cu" "In16.Cu"
			)
			(hatch none 0.5)
			(connect_pads
				(clearance 0)
			)
			(min_thickness 0.25)
			(keepout
				(tracks not_allowed)
				(vias allowed)
				(pads allowed)
				(copperpour not_allowed)
				(footprints allowed)
			)
			(placement
				(enabled no)
				(sheetname "")
			)
			(fill
				(thermal_gap 0.5)
				(thermal_bridge_width 0.5)
				(island_removal_mode 0)
			)
			(polygon
				(pts
					(arc
						(start 375.559574 4.193794)
						(mid 373.705374 4.193794)
						(end 375.559574 4.193794)
					)
				)
			)
		)
		(zone
			(layers "F.Cu" "B.Cu" "In1.Cu" "In2.Cu" "In3.Cu" "In4.Cu" "In5.Cu" "In6.Cu"
				"In7.Cu" "In8.Cu" "In9.Cu" "In10.Cu" "In11.Cu" "In12.Cu" "In13.Cu" "In14.Cu"
				"In15.Cu" "In16.Cu"
			)
			(hatch none 0.5)
			(connect_pads
				(clearance 0)
			)
			(min_thickness 0.25)
			(keepout
				(tracks not_allowed)
				(vias allowed)
				(pads allowed)
				(copperpour not_allowed)
				(footprints allowed)
			)
			(placement
				(enabled no)
				(sheetname "")
			)
			(fill
				(thermal_gap 0.5)
				(thermal_bridge_width 0.5)
				(island_removal_mode 0)
			)
			(polygon
				(pts
					(arc
						(start 381.909574 1.653794)
						(mid 380.055374 1.653794)
						(end 381.909574 1.653794)
					)
				)
			)
		)
		(zone
			(layers "F.Cu" "B.Cu" "In1.Cu" "In2.Cu" "In3.Cu" "In4.Cu" "In5.Cu" "In6.Cu"
				"In7.Cu" "In8.Cu" "In9.Cu" "In10.Cu" "In11.Cu" "In12.Cu" "In13.Cu" "In14.Cu"
				"In15.Cu" "In16.Cu"
			)
			(hatch none 0.5)
			(connect_pads
				(clearance 0)
			)
			(min_thickness 0.25)
			(keepout
				(tracks not_allowed)
				(vias allowed)
				(pads allowed)
				(copperpour not_allowed)
				(footprints allowed)
			)
			(placement
				(enabled no)
				(sheetname "")
			)
			(fill
				(thermal_gap 0.5)
				(thermal_bridge_width 0.5)
				(island_removal_mode 0)
			)
			(polygon
				(pts
					(arc
						(start 381.909574 4.193794)
						(mid 380.055374 4.193794)
						(end 381.909574 4.193794)
					)
				)
			)
		)
		(zone
			(layer "B.Cu")
			(hatch none 0.5)
			(connect_pads
				(clearance 0)
			)
			(min_thickness 0.25)
			(keepout
				(tracks not_allowed)
				(vias allowed)
				(pads allowed)
				(copperpour not_allowed)
				(footprints allowed)
			)
			(placement
				(enabled no)
				(sheetname "")
			)
			(fill
				(thermal_gap 0.5)
				(thermal_bridge_width 0.5)
				(island_removal_mode 0)
			)
			(polygon
				(pts
					(xy 376.981974 2.375154) (xy 376.981974 2.470658) (xy 377.578874 2.470658) (xy 377.578874 2.877058)
					(xy 376.981974 2.877058) (xy 376.981974 2.97053) (xy 377.578874 2.97053) (xy 377.578874 3.37693)
					(xy 376.981974 3.37693) (xy 376.981974 3.472434) (xy 377.680474 3.472434) (xy 377.680474 2.375154)
				)
			)
		)
	)
)
